# S9S_MB_2U (Grand Teton) — schematic netlist excerpt (pin names and nets, part order shuffled) for the footprints in the layout excerpt that follows; sources: Cadence DE-HDL packaged netlist, KiCad conversion of 03242023_DA0F0TMBIJ0_F0T_Motherboard_J_brd_V01_OCP.brd

D77  Q_LED  IC  pkg SMLF  page 253 : A = LED_PWRGD_PVCCINFAON_CPU0 ; C = LED_PWRGD_PVCCINFAON_CPU0_D
R3036  Q_RES  33.2 1% CHIP  pkg 0402LF  page 151 : A = UART_BMC_BIC_R_BUF_RX ; B = UART_BMC_BIC_BUF_RX

(kicad_pcb
	(version 20260206)
	(generator "pcbnew")
	(generator_version "10.0")
	(general
		(thickness 1.6)
		(legacy_teardrops no)
	)
	(paper "A4")
	(title_block
		(title "03242023_DA0F0TMBIJ0_F0T_Motherboard_J_brd_V01_OCP.brd")
		(comment 1 "Grand Teton / footprints 3192-3193 of 6105")
	)
	(layers
		(0 "F.Cu" signal "TOP")
		(4 "In1.Cu" signal "GND")
		(6 "In2.Cu" signal "IN1")
		(8 "In3.Cu" signal "GND1")
		(10 "In4.Cu" signal "IN2")
		(12 "In5.Cu" signal "GND2")
		(14 "In6.Cu" signal "IN3")
		(16 "In7.Cu" signal "GND3")
		(18 "In8.Cu" signal "VCC")
		(20 "In9.Cu" signal "VCC1")
		(22 "In10.Cu" signal "GND4")
		(24 "In11.Cu" signal "IN4")
		(26 "In12.Cu" signal "GND5")
		(28 "In13.Cu" signal "IN5")
		(30 "In14.Cu" signal "GND6")
		(32 "In15.Cu" signal "IN6")
		(34 "In16.Cu" signal "GND7")
		(2 "B.Cu" signal "BOTTOM")
		(9 "F.Adhes" user "F.Adhesive")
		(11 "B.Adhes" user "B.Adhesive")
		(13 "F.Paste" user "Package Geometry/Pastemask Top")
		(15 "B.Paste" user "Package Geometry/Pastemask Bottom")
		(5 "F.SilkS" user "Ref Des/Silkscreen Top")
		(7 "B.SilkS" user "Ref Des/Silkscreen Bottom")
		(1 "F.Mask" user "Board Geometry/Soldermask Top")
		(3 "B.Mask" user "Board Geometry/Soldermask Bottom")
		(17 "Dwgs.User" user "User.Drawings")
		(19 "Cmts.User" user "User.Comments")
		(21 "Eco1.User" user "User.Eco1")
		(23 "Eco2.User" user "User.Eco2")
		(25 "Edge.Cuts" user "Board Geometry/Outline")
		(27 "Margin" user)
		(31 "F.CrtYd" user "Package Geometry/Place Bound Top")
		(29 "B.CrtYd" user "Package Geometry/Place Bound Bottom")
		(35 "F.Fab" user "Ref Des/Assembly Top")
		(33 "B.Fab" user "Ref Des/Assembly Bottom")
	)
	(footprint ""
		(layer "F.Cu")
		(at 368.71402 -402.910548)
		(property "Reference" "R3036"
			(at 0 0 0)
			(layer "F.SilkS")
			(hide yes)
			(effects
				(font
					(size 1.27 1.27)
				)
			)
		)
		(property "Value" ""
			(at 0 0 0)
			(layer "F.Fab")
			(effects
				(font
					(size 1.27 1.27)
				)
			)
		)
		(duplicate_pad_numbers_are_jumpers no)
		(fp_line
			(start -0.7874 -0.4064)
			(end 0.7874 -0.4064)
			(stroke
				(width 0.1524)
				(type default)
			)
			(layer "F.SilkS")
		)
		(fp_line
			(start -0.7874 0.4064)
			(end -0.7874 -0.4064)
			(stroke
				(width 0.1524)
				(type default)
			)
			(layer "F.SilkS")
		)
		(fp_line
			(start 0.7874 -0.4064)
			(end 0.7874 0.4064)
			(stroke
				(width 0.1524)
				(type default)
			)
			(layer "F.SilkS")
		)
		(fp_line
			(start 0.7874 0.4064)
			(end -0.7874 0.4064)
			(stroke
				(width 0.1524)
				(type default)
			)
			(layer "F.SilkS")
		)
		(fp_line
			(start -0.67945 -0.305054)
			(end -0.12065 -0.305054)
			(stroke
				(width 0.1)
				(type default)
			)
			(layer "F.Fab")
		)
		(fp_line
			(start -0.67945 0.3048)
			(end -0.67945 -0.305054)
			(stroke
				(width 0.1)
				(type default)
			)
			(layer "F.Fab")
		)
		(fp_line
			(start -0.12065 -0.305054)
			(end -0.12065 -0.2794)
			(stroke
				(width 0.1)
				(type default)
			)
			(layer "F.Fab")
		)
		(fp_line
			(start -0.12065 -0.2794)
			(end 0.12065 -0.2794)
			(stroke
				(width 0.1)
				(type default)
			)
			(layer "F.Fab")
		)
		(fp_line
			(start -0.12065 0.2794)
			(end -0.12065 0.3048)
			(stroke
				(width 0.1)
				(type default)
			)
			(layer "F.Fab")
		)
		(fp_line
			(start -0.12065 0.3048)
			(end -0.67945 0.3048)
			(stroke
				(width 0.1)
				(type default)
			)
			(layer "F.Fab")
		)
		(fp_line
			(start 0.120396 0.2794)
			(end -0.12065 0.2794)
			(stroke
				(width 0.1)
				(type default)
			)
			(layer "F.Fab")
		)
		(fp_line
			(start 0.120396 0.3048)
			(end 0.120396 0.2794)
			(stroke
				(width 0.1)
				(type default)
			)
			(layer "F.Fab")
		)
		(fp_line
			(start 0.12065 -0.3048)
			(end 0.67945 -0.3048)
			(stroke
				(width 0.1)
				(type default)
			)
			(layer "F.Fab")
		)
		(fp_line
			(start 0.12065 -0.2794)
			(end 0.12065 -0.3048)
			(stroke
				(width 0.1)
				(type default)
			)
			(layer "F.Fab")
		)
		(fp_line
			(start 0.67945 -0.3048)
			(end 0.67945 0.3048)
			(stroke
				(width 0.1)
				(type default)
			)
			(layer "F.Fab")
		)
		(fp_line
			(start 0.67945 0.3048)
			(end 0.120396 0.3048)
			(stroke
				(width 0.1)
				(type default)
			)
			(layer "F.Fab")
		)
		(pad "1" smd circle
			(at -0.40005 0)
			(size 0 0)
			(layers "F.Cu" "F.Mask" "F.Paste")
			(net "UART_BMC_BIC_R_BUF_RX")
		)
		(pad "2" smd circle
			(at 0.40005 0)
			(size 0 0)
			(layers "F.Cu" "F.Mask" "F.Paste")
			(net "UART_BMC_BIC_BUF_RX")
		)
	)
	(footprint ""
		(layer "F.Cu")
		(at 58.393076 -79.078836)
		(property "Reference" "D77"
			(at -31.599886 34.341308 90)
			(unlocked yes)
			(layer "F.SilkS")
			(effects
				(font
					(size 0.635 0.4064)
					(thickness 0.1524)
				)
				(justify left)
			)
		)
		(property "Value" ""
			(at 0 0 0)
			(layer "F.Fab")
			(effects
				(font
					(size 1.27 1.27)
				)
			)
		)
		(duplicate_pad_numbers_are_jumpers no)
		(fp_line
			(start -0.90678 0.4826)
			(end -0.90678 -0.4699)
			(stroke
				(width 0.1524)
				(type default)
			)
			(layer "F.SilkS")
		)
		(fp_line
			(start -0.89408 -0.4826)
			(end 0.90678 -0.4826)
			(stroke
				(width 0.1524)
				(type default)
			)
			(layer "F.SilkS")
		)
		(fp_line
			(start -0.79248 -0.4826)
			(end 1.03378 -0.4826)
			(stroke
				(width 0.1524)
				(type default)
			)
			(layer "F.SilkS")
		)
		(fp_line
			(start -0.64008 -0.4826)
			(end 1.16078 -0.4826)
			(stroke
				(width 0.1524)
				(type default)
			)
			(layer "F.SilkS")
		)
		(fp_line
			(start 0.90678 -0.4826)
			(end 0.90678 0.4826)
			(stroke
				(width 0.1524)
				(type default)
			)
			(layer "F.SilkS")
		)
		(fp_line
			(start 0.90678 0.4826)
			(end -0.90678 0.4826)
			(stroke
				(width 0.1524)
				(type default)
			)
			(layer "F.SilkS")
		)
		(fp_line
			(start 1.03378 -0.4826)
			(end 1.03378 0.4826)
			(stroke
				(width 0.1524)
				(type default)
			)
			(layer "F.SilkS")
		)
		(fp_line
			(start 1.03378 0.4826)
			(end -0.79248 0.4826)
			(stroke
				(width 0.1524)
				(type default)
			)
			(layer "F.SilkS")
		)
		(fp_line
			(start 1.16078 -0.4826)
			(end 1.16078 0.4826)
			(stroke
				(width 0.1524)
				(type default)
			)
			(layer "F.SilkS")
		)
		(fp_line
			(start 1.16078 0.4826)
			(end -0.64008 0.4826)
			(stroke
				(width 0.1524)
				(type default)
			)
			(layer "F.SilkS")
		)
		(fp_line
			(start -0.499872 -0.249936)
			(end 0.499872 -0.249936)
			(stroke
				(width 0.1)
				(type default)
			)
			(layer "F.Fab")
		)
		(fp_line
			(start -0.499872 0.249936)
			(end -0.499872 -0.249936)
			(stroke
				(width 0.1)
				(type default)
			)
			(layer "F.Fab")
		)
		(fp_line
			(start 0.499872 -0.249936)
			(end 0.499872 0.249936)
			(stroke
				(width 0.1)
				(type default)
			)
			(layer "F.Fab")
		)
		(fp_line
			(start 0.499872 0.249936)
			(end -0.499872 0.249936)
			(stroke
				(width 0.1)
				(type default)
			)
			(layer "F.Fab")
		)
		(pad "A" smd rect
			(at -0.47498 0)
			(size 0.6096 0.7112)
			(layers "F.Cu" "F.Mask" "F.Paste")
			(net "LED_PWRGD_PVCCINFAON_CPU0")
		)
		(pad "C" smd rect
			(at 0.47498 0)
			(size 0.6096 0.7112)
			(layers "F.Cu" "F.Mask" "F.Paste")
			(net "LED_PWRGD_PVCCINFAON_CPU0_D")
		)
	)
)
